(kicad_pcb
	(version 20260206)
	(generator "pcbnew")
	(generator_version "10.0")
	(general
		(thickness 1.6)
		(legacy_teardrops no)
	)
	(paper "A4")
	(title_block
		(title "peb — Lightning_PEB_BRD.brd")
		(comment 1 "Lightning (Wiwynn / Facebook NVMe JBOF) / footprints 640-647 of 2563")
	)
	(layers
		(0 "F.Cu" signal "TOP")
		(4 "In1.Cu" signal "L2GND")
		(6 "In2.Cu" signal "L3")
		(8 "In3.Cu" signal "L4VCC")
		(10 "In4.Cu" signal "L5VCC")
		(12 "In5.Cu" signal "L6")
		(14 "In6.Cu" signal "L7GND")
		(2 "B.Cu" signal "BOTTOM")
		(9 "F.Adhes" user "F.Adhesive")
		(11 "B.Adhes" user "B.Adhesive")
		(13 "F.Paste" user "Package Geometry/Pastemask Top")
		(15 "B.Paste" user "Package Geometry/Pastemask Bottom")
		(5 "F.SilkS" user "Ref Des/Silkscreen Top")
		(7 "B.SilkS" user "Ref Des/Silkscreen Bottom")
		(1 "F.Mask" user "Board Geometry/Soldermask Top")
		(3 "B.Mask" user "Board Geometry/Soldermask Bottom")
		(17 "Dwgs.User" user "User.Drawings")
		(19 "Cmts.User" user "User.Comments")
		(21 "Eco1.User" user "User.Eco1")
		(23 "Eco2.User" user "User.Eco2")
		(25 "Edge.Cuts" user "Board Geometry/Outline")
		(27 "Margin" user)
		(31 "F.CrtYd" user "Package Geometry/Place Bound Top")
		(29 "B.CrtYd" user "Package Geometry/Place Bound Bottom")
		(35 "F.Fab" user "Ref Des/Assembly Top")
		(33 "B.Fab" user "Ref Des/Assembly Bottom")
	)
	(footprint ""
		(layer "F.Cu")
		(at 345.217496 -43.97248)
		(property "Reference" "R694"
			(at 0 0 0)
			(layer "F.SilkS")
			(hide yes)
			(effects
				(font
					(size 1.27 1.27)
				)
			)
		)
		(property "Value" "4K7R2F-GP"
			(at 0.064008 -3.993896 0)
			(unlocked yes)
			(layer "F.Fab")
			(hide yes)
			(effects
				(font
					(size 1.016 1.016)
					(thickness 0.1524)
				)
			)
		)
		(property "Device Type" "R402H16"
			(at 0.064008 -5.517896 0)
			(unlocked yes)
			(layer "F.Fab")
			(hide yes)
			(effects
				(font
					(size 1.016 1.016)
					(thickness 0.1524)
				)
			)
		)
		(duplicate_pad_numbers_are_jumpers no)
		(fp_line
			(start -0.508 -0.9398)
			(end -0.508 0.9398)
			(stroke
				(width 0.1524)
				(type default)
			)
			(layer "F.SilkS")
		)
		(fp_line
			(start 0.508 -0.9398)
			(end -0.508 -0.9398)
			(stroke
				(width 0.1524)
				(type default)
			)
			(layer "F.SilkS")
		)
		(fp_rect
			(start -0.508 0.9398)
			(end 0.508 -0.9398)
			(stroke
				(width 0)
				(type default)
			)
			(fill no)
			(layer "F.CrtYd")
		)
		(fp_rect
			(start -0.508 0.9398)
			(end 0.508 -0.9398)
			(stroke
				(width 0)
				(type default)
			)
			(fill no)
			(layer "F.Fab")
		)
		(pad "1" smd custom
			(at 0 -0.4445)
			(size 0.1397 0.1397)
			(layers "F.Cu" "F.Mask" "F.Paste")
			(net "PM8536_RST#_LS")
			(options
				(clearance outline)
				(anchor circle)
			)
			(primitives
				(gr_poly
					(pts
						(arc
							(start -0.1778 -0.2794)
							(mid -0.249642 -0.249642)
							(end -0.2794 -0.1778)
						)
						(arc
							(start -0.2794 0.1778)
							(mid -0.249642 0.249642)
							(end -0.1778 0.2794)
						)
						(arc
							(start 0.1778 0.2794)
							(mid 0.249642 0.249642)
							(end 0.2794 0.1778)
						)
						(arc
							(start 0.2794 -0.1778)
							(mid 0.249642 -0.249642)
							(end 0.1778 -0.2794)
						)
					)
					(width 0)
					(fill yes)
				)
			)
		)
		(pad "2" smd custom
			(at 0 0.4445)
			(size 0.1397 0.1397)
			(layers "F.Cu" "F.Mask" "F.Paste")
			(net "P3V3_STBY")
			(options
				(clearance outline)
				(anchor circle)
			)
			(primitives
				(gr_poly
					(pts
						(arc
							(start -0.1778 -0.2794)
							(mid -0.249642 -0.249642)
							(end -0.2794 -0.1778)
						)
						(arc
							(start -0.2794 0.1778)
							(mid -0.249642 0.249642)
							(end -0.1778 0.2794)
						)
						(arc
							(start 0.1778 0.2794)
							(mid 0.249642 0.249642)
							(end 0.2794 0.1778)
						)
						(arc
							(start 0.2794 -0.1778)
							(mid 0.249642 -0.249642)
							(end 0.1778 -0.2794)
						)
					)
					(width 0)
					(fill yes)
				)
			)
		)
	)
	(footprint ""
		(layer "F.Cu")
		(at 151.527002 -69.699632 90)
		(property "Reference" "PC210"
			(at 0 0 90)
			(layer "F.SilkS")
			(hide yes)
			(effects
				(font
					(size 1.27 1.27)
				)
			)
		)
		(property "Value" "SC22U25V6KX-GP-U"
			(at -2.860802 -5.279644 90)
			(unlocked yes)
			(layer "F.Fab")
			(hide yes)
			(effects
				(font
					(size 1.016 1.016)
					(thickness 0.1524)
				)
			)
		)
		(property "Device Type" "C1206-TO0D3H75"
			(at -2.860802 -6.803644 90)
			(unlocked yes)
			(layer "F.Fab")
			(hide yes)
			(effects
				(font
					(size 1.016 1.016)
					(thickness 0.1524)
				)
			)
		)
		(duplicate_pad_numbers_are_jumpers no)
		(fp_line
			(start 1.3081 -2.3749)
			(end 1.3081 2.3749)
			(stroke
				(width 0.1524)
				(type default)
			)
			(layer "F.SilkS")
		)
		(fp_line
			(start -1.3081 -2.3749)
			(end 1.3081 -2.3749)
			(stroke
				(width 0.1524)
				(type default)
			)
			(layer "F.SilkS")
		)
		(fp_line
			(start 1.3081 2.3749)
			(end -1.3081 2.3749)
			(stroke
				(width 0.1524)
				(type default)
			)
			(layer "F.SilkS")
		)
		(fp_line
			(start -1.3081 2.3749)
			(end -1.3081 -2.3749)
			(stroke
				(width 0.1524)
				(type default)
			)
			(layer "F.SilkS")
		)
		(fp_rect
			(start -0.8001 1.6002)
			(end 0.8001 -1.6002)
			(stroke
				(width 0)
				(type default)
			)
			(fill no)
			(layer "F.CrtYd")
		)
		(fp_poly
			(pts
				(xy -1.5621 2.4511) (xy -1.5621 1.6002) (xy 0.8001 1.6002) (xy 0.8001 -1.6002) (xy -0.8001 -1.6002)
				(xy -0.8001 1.5875) (xy -1.5621 1.5875) (xy -1.5621 -2.4511) (xy 1.5621 -2.4511) (xy 1.5621 2.4511)
			)
			(stroke
				(width 0)
				(type default)
			)
			(fill no)
			(layer "F.CrtYd")
		)
		(fp_rect
			(start -1.5621 2.4511)
			(end 1.5621 -2.4511)
			(stroke
				(width 0)
				(type default)
			)
			(fill no)
			(layer "F.Fab")
		)
		(pad "1" smd rect
			(at 0 -1.392936 90)
			(size 2.1082 1.4478)
			(layers "F.Cu" "F.Mask" "F.Paste")
			(net "P0V9_VIN")
		)
		(pad "2" smd rect
			(at 0 1.392936 90)
			(size 2.1082 1.4478)
			(layers "F.Cu" "F.Mask" "F.Paste")
			(net "GND")
		)
	)
	(footprint ""
		(layer "F.Cu")
		(at 336.60588 -31.90748 180)
		(property "Reference" "Q29"
			(at 0 0 180)
			(layer "F.SilkS")
			(hide yes)
			(effects
				(font
					(size 1.27 1.27)
				)
			)
		)
		(property "Value" "2N7002K-1-GP"
			(at 0.127 -8.9662 180)
			(unlocked yes)
			(layer "F.Fab")
			(hide yes)
			(effects
				(font
					(size 1.016 1.016)
					(thickness 0.1524)
				)
			)
		)
		(property "Device Type" "SOT23DGS2D4H44"
			(at 0.127 -10.4902 180)
			(unlocked yes)
			(layer "F.Fab")
			(hide yes)
			(effects
				(font
					(size 1.016 1.016)
					(thickness 0.1524)
				)
			)
		)
		(duplicate_pad_numbers_are_jumpers no)
		(fp_line
			(start 1.651 1.778)
			(end 1.651 -1.778)
			(stroke
				(width 0.1524)
				(type default)
			)
			(layer "F.SilkS")
		)
		(fp_line
			(start 1.651 -1.778)
			(end -1.651 -1.778)
			(stroke
				(width 0.1524)
				(type default)
			)
			(layer "F.SilkS")
		)
		(fp_line
			(start -1.651 1.778)
			(end 1.651 1.778)
			(stroke
				(width 0.1524)
				(type default)
			)
			(layer "F.SilkS")
		)
		(fp_line
			(start -1.651 -1.778)
			(end -1.651 1.778)
			(stroke
				(width 0.1524)
				(type default)
			)
			(layer "F.SilkS")
		)
		(fp_poly
			(pts
				(xy -1.778 1.8796) (xy -1.778 -1.8796) (xy 1.778 -1.8796) (xy 1.778 1.8796)
			)
			(stroke
				(width 0)
				(type default)
			)
			(fill no)
			(layer "F.CrtYd")
		)
		(fp_poly
			(pts
				(xy -1.778 1.8796) (xy -1.778 -1.8796) (xy 1.778 -1.8796) (xy 1.778 1.8796)
			)
			(stroke
				(width 0)
				(type default)
			)
			(fill no)
			(layer "F.Fab")
		)
		(pad "D" smd custom
			(at 0 -0.9525 180)
			(size 0.1905 0.1905)
			(layers "F.Cu" "F.Mask" "F.Paste")
			(net "LED_Q_8")
			(options
				(clearance outline)
				(anchor circle)
			)
			(primitives
				(gr_poly
					(pts
						(arc
							(start -0.1778 0.5715)
							(mid -0.321484 0.511984)
							(end -0.381 0.3683)
						)
						(arc
							(start -0.381 -0.3683)
							(mid -0.321484 -0.511984)
							(end -0.1778 -0.5715)
						)
						(arc
							(start 0.1778 -0.5715)
							(mid 0.321484 -0.511984)
							(end 0.381 -0.3683)
						)
						(arc
							(start 0.381 0.3683)
							(mid 0.321484 0.511984)
							(end 0.1778 0.5715)
						)
					)
					(width 0)
					(fill yes)
				)
			)
		)
		(pad "G" smd custom
			(at -0.98425 0.9525 180)
			(size 0.1905 0.1905)
			(layers "F.Cu" "F.Mask" "F.Paste")
			(net "UPLINK8_R")
			(options
				(clearance outline)
				(anchor circle)
			)
			(primitives
				(gr_poly
					(pts
						(arc
							(start -0.1778 0.5715)
							(mid -0.321484 0.511984)
							(end -0.381 0.3683)
						)
						(arc
							(start -0.381 -0.3683)
							(mid -0.321484 -0.511984)
							(end -0.1778 -0.5715)
						)
						(arc
							(start 0.1778 -0.5715)
							(mid 0.321484 -0.511984)
							(end 0.381 -0.3683)
						)
						(arc
							(start 0.381 0.3683)
							(mid 0.321484 0.511984)
							(end 0.1778 0.5715)
						)
					)
					(width 0)
					(fill yes)
				)
			)
		)
		(pad "S" smd custom
			(at 0.98425 0.9525 180)
			(size 0.1905 0.1905)
			(layers "F.Cu" "F.Mask" "F.Paste")
			(net "GND")
			(options
				(clearance outline)
				(anchor circle)
			)
			(primitives
				(gr_poly
					(pts
						(arc
							(start -0.1778 0.5715)
							(mid -0.321484 0.511984)
							(end -0.381 0.3683)
						)
						(arc
							(start -0.381 -0.3683)
							(mid -0.321484 -0.511984)
							(end -0.1778 -0.5715)
						)
						(arc
							(start 0.1778 -0.5715)
							(mid 0.321484 -0.511984)
							(end 0.381 -0.3683)
						)
						(arc
							(start 0.381 0.3683)
							(mid 0.321484 0.511984)
							(end 0.1778 0.5715)
						)
					)
					(width 0)
					(fill yes)
				)
			)
		)
	)
	(footprint ""
		(layer "F.Cu")
		(at 191.897 -16.256 90)
		(property "Reference" "SR716"
			(at 0 0 90)
			(layer "F.SilkS")
			(hide yes)
			(effects
				(font
					(size 1.27 1.27)
				)
			)
		)
		(property "Value" "150R2F-1-GP"
			(at 0.064008 -3.993896 90)
			(unlocked yes)
			(layer "F.Fab")
			(hide yes)
			(effects
				(font
					(size 1.016 1.016)
					(thickness 0.1524)
				)
			)
		)
		(property "Device Type" "R402H16"
			(at 0.064008 -5.517896 90)
			(unlocked yes)
			(layer "F.Fab")
			(hide yes)
			(effects
				(font
					(size 1.016 1.016)
					(thickness 0.1524)
				)
			)
		)
		(duplicate_pad_numbers_are_jumpers no)
		(fp_line
			(start 0.508 -0.9398)
			(end -0.508 -0.9398)
			(stroke
				(width 0.1524)
				(type default)
			)
			(layer "F.SilkS")
		)
		(fp_line
			(start -0.508 -0.9398)
			(end -0.508 0.9398)
			(stroke
				(width 0.1524)
				(type default)
			)
			(layer "F.SilkS")
		)
		(fp_rect
			(start -0.508 0.9398)
			(end 0.508 -0.9398)
			(stroke
				(width 0)
				(type default)
			)
			(fill no)
			(layer "F.CrtYd")
		)
		(fp_rect
			(start -0.508 0.9398)
			(end 0.508 -0.9398)
			(stroke
				(width 0)
				(type default)
			)
			(fill no)
			(layer "F.Fab")
		)
		(pad "1" smd custom
			(at 0 -0.4445 90)
			(size 0.1397 0.1397)
			(layers "F.Cu" "F.Mask" "F.Paste")
			(net "P3V3_STBY")
			(options
				(clearance outline)
				(anchor circle)
			)
			(primitives
				(gr_poly
					(pts
						(arc
							(start -0.1778 -0.2794)
							(mid -0.249642 -0.249642)
							(end -0.2794 -0.1778)
						)
						(arc
							(start -0.2794 0.1778)
							(mid -0.249642 0.249642)
							(end -0.1778 0.2794)
						)
						(arc
							(start 0.1778 0.2794)
							(mid 0.249642 0.249642)
							(end 0.2794 0.1778)
						)
						(arc
							(start 0.2794 -0.1778)
							(mid 0.249642 -0.249642)
							(end 0.1778 -0.2794)
						)
					)
					(width 0)
					(fill yes)
				)
			)
		)
		(pad "2" smd custom
			(at 0 0.4445 90)
			(size 0.1397 0.1397)
			(layers "F.Cu" "F.Mask" "F.Paste")
			(net "LED_R_11")
			(options
				(clearance outline)
				(anchor circle)
			)
			(primitives
				(gr_poly
					(pts
						(arc
							(start -0.1778 -0.2794)
							(mid -0.249642 -0.249642)
							(end -0.2794 -0.1778)
						)
						(arc
							(start -0.2794 0.1778)
							(mid -0.249642 0.249642)
							(end -0.1778 0.2794)
						)
						(arc
							(start 0.1778 0.2794)
							(mid 0.249642 0.249642)
							(end 0.2794 0.1778)
						)
						(arc
							(start 0.2794 -0.1778)
							(mid 0.249642 -0.249642)
							(end 0.1778 -0.2794)
						)
					)
					(width 0)
					(fill yes)
				)
			)
		)
	)
	(footprint ""
		(layer "F.Cu")
		(at 38.1508 -186.5376)
		(property "Reference" "C700"
			(at 0 0 0)
			(layer "F.SilkS")
			(hide yes)
			(effects
				(font
					(size 1.27 1.27)
				)
			)
		)
		(property "Value" "SCD1U16V2KX-3GP"
			(at 1.1811 -2.7051 0)
			(unlocked yes)
			(layer "F.Fab")
			(hide yes)
			(effects
				(font
					(size 1.016 1.016)
					(thickness 0.1524)
				)
			)
		)
		(property "Device Type" "C402H22"
			(at 1.1811 -4.2291 0)
			(unlocked yes)
			(layer "F.Fab")
			(hide yes)
			(effects
				(font
					(size 1.016 1.016)
					(thickness 0.1524)
				)
			)
		)
		(duplicate_pad_numbers_are_jumpers no)
		(fp_rect
			(start -0.4318 0.9525)
			(end 0.4318 -0.9525)
			(stroke
				(width 0)
				(type default)
			)
			(fill no)
			(layer "F.CrtYd")
		)
		(fp_rect
			(start -0.4318 0.9525)
			(end 0.4318 -0.9525)
			(stroke
				(width 0)
				(type default)
			)
			(fill no)
			(layer "F.Fab")
		)
		(pad "1" smd custom
			(at 0 -0.4445)
			(size 0.1524 0.1524)
			(layers "F.Cu" "F.Mask" "F.Paste")
			(net "P3V3_STBY")
			(options
				(clearance outline)
				(anchor circle)
			)
			(primitives
				(gr_poly
					(pts
						(arc
							(start 0.3048 -0.2032)
							(mid 0.275042 -0.275042)
							(end 0.2032 -0.3048)
						)
						(arc
							(start -0.2032 -0.3048)
							(mid -0.275042 -0.275042)
							(end -0.3048 -0.2032)
						)
						(arc
							(start -0.3048 0.2032)
							(mid -0.275042 0.275042)
							(end -0.2032 0.3048)
						)
						(arc
							(start 0.2032 0.3048)
							(mid 0.275042 0.275042)
							(end 0.3048 0.2032)
						)
					)
					(width 0)
					(fill yes)
				)
			)
		)
		(pad "2" smd custom
			(at 0 0.4445)
			(size 0.1524 0.1524)
			(layers "F.Cu" "F.Mask" "F.Paste")
			(net "GND")
			(options
				(clearance outline)
				(anchor circle)
			)
			(primitives
				(gr_poly
					(pts
						(arc
							(start 0.3048 -0.2032)
							(mid 0.275042 -0.275042)
							(end 0.2032 -0.3048)
						)
						(arc
							(start -0.2032 -0.3048)
							(mid -0.275042 -0.275042)
							(end -0.3048 -0.2032)
						)
						(arc
							(start -0.3048 0.2032)
							(mid -0.275042 0.275042)
							(end -0.2032 0.3048)
						)
						(arc
							(start 0.2032 0.3048)
							(mid 0.275042 0.275042)
							(end 0.3048 0.2032)
						)
					)
					(width 0)
					(fill yes)
				)
			)
		)
	)
	(footprint ""
		(layer "F.Cu")
		(at 252.10516 -4.74345 180)
		(property "Reference" "TP234"
			(at 0 0 180)
			(layer "F.SilkS")
			(hide yes)
			(effects
				(font
					(size 1.27 1.27)
				)
			)
		)
		(property "Value" "TPAD28-2-GP"
			(at -0.0127 -1.6637 180)
			(unlocked yes)
			(layer "F.Fab")
			(hide yes)
			(effects
				(font
					(size 1.016 1.016)
					(thickness 0.1524)
				)
			)
		)
		(property "Device Type" "TPAD28"
			(at -0.0127 -3.1877 180)
			(unlocked yes)
			(layer "F.Fab")
			(hide yes)
			(effects
				(font
					(size 1.016 1.016)
					(thickness 0.1524)
				)
			)
		)
		(duplicate_pad_numbers_are_jumpers no)
		(fp_poly
			(pts
				(arc
					(start -0.3556 0)
					(mid 0.3556 0)
					(end -0.3556 0)
				)
			)
			(stroke
				(width 0)
				(type default)
			)
			(fill no)
			(layer "F.CrtYd")
		)
		(fp_poly
			(pts
				(arc
					(start -0.6096 0)
					(mid 0.6096 0)
					(end -0.6096 0)
				)
			)
			(stroke
				(width 0)
				(type default)
			)
			(fill no)
			(layer "F.Fab")
		)
		(pad "1" smd circle
			(at 0 0 180)
			(size 0.7112 0.7112)
			(layers "F.Cu" "F.Mask" "F.Paste")
			(net "MAX6654_ALERT#")
		)
	)
	(footprint ""
		(layer "F.Cu")
		(at 318.516 -99.568 180)
		(property "Reference" "C3701"
			(at 0 0 180)
			(layer "F.SilkS")
			(hide yes)
			(effects
				(font
					(size 1.27 1.27)
				)
			)
		)
		(property "Value" "SCD1U25V2KX-2-GP"
			(at 1.1811 -2.7051 180)
			(unlocked yes)
			(layer "F.Fab")
			(hide yes)
			(effects
				(font
					(size 1.016 1.016)
					(thickness 0.1524)
				)
			)
		)
		(property "Device Type" "C402H22"
			(at 1.1811 -4.2291 180)
			(unlocked yes)
			(layer "F.Fab")
			(hide yes)
			(effects
				(font
					(size 1.016 1.016)
					(thickness 0.1524)
				)
			)
		)
		(duplicate_pad_numbers_are_jumpers no)
		(fp_rect
			(start -0.4318 0.9525)
			(end 0.4318 -0.9525)
			(stroke
				(width 0)
				(type default)
			)
			(fill no)
			(layer "F.CrtYd")
		)
		(fp_rect
			(start -0.4318 0.9525)
			(end 0.4318 -0.9525)
			(stroke
				(width 0)
				(type default)
			)
			(fill no)
			(layer "F.Fab")
		)
		(pad "1" smd custom
			(at 0 -0.4445 180)
			(size 0.1524 0.1524)
			(layers "F.Cu" "F.Mask" "F.Paste")
			(net "P3V3_STBY")
			(options
				(clearance outline)
				(anchor circle)
			)
			(primitives
				(gr_poly
					(pts
						(arc
							(start 0.3048 -0.2032)
							(mid 0.275042 -0.275042)
							(end 0.2032 -0.3048)
						)
						(arc
							(start -0.2032 -0.3048)
							(mid -0.275042 -0.275042)
							(end -0.3048 -0.2032)
						)
						(arc
							(start -0.3048 0.2032)
							(mid -0.275042 0.275042)
							(end -0.2032 0.3048)
						)
						(arc
							(start 0.2032 0.3048)
							(mid 0.275042 0.275042)
							(end 0.3048 0.2032)
						)
					)
					(width 0)
					(fill yes)
				)
			)
		)
		(pad "2" smd custom
			(at 0 0.4445 180)
			(size 0.1524 0.1524)
			(layers "F.Cu" "F.Mask" "F.Paste")
			(net "GND")
			(options
				(clearance outline)
				(anchor circle)
			)
			(primitives
				(gr_poly
					(pts
						(arc
							(start 0.3048 -0.2032)
							(mid 0.275042 -0.275042)
							(end 0.2032 -0.3048)
						)
						(arc
							(start -0.2032 -0.3048)
							(mid -0.275042 -0.275042)
							(end -0.3048 -0.2032)
						)
						(arc
							(start -0.3048 0.2032)
							(mid -0.275042 0.275042)
							(end -0.2032 0.3048)
						)
						(arc
							(start 0.2032 0.3048)
							(mid 0.275042 0.275042)
							(end 0.3048 0.2032)
						)
					)
					(width 0)
					(fill yes)
				)
			)
		)
	)
	(footprint ""
		(layer "F.Cu")
		(at 134.1882 -40.05961 -90)
		(property "Reference" "R759"
			(at 0 0 270)
			(layer "F.SilkS")
			(hide yes)
			(effects
				(font
					(size 1.27 1.27)
				)
			)
		)
		(property "Value" "0R2J-2-GP"
			(at 0.064008 -3.993896 270)
			(unlocked yes)
			(layer "F.Fab")
			(hide yes)
			(effects
				(font
					(size 1.016 1.016)
					(thickness 0.1524)
				)
			)
		)
		(property "Device Type" "R402H16"
			(at 0.064008 -5.517896 270)
			(unlocked yes)
			(layer "F.Fab")
			(hide yes)
			(effects
				(font
					(size 1.016 1.016)
					(thickness 0.1524)
				)
			)
		)
		(duplicate_pad_numbers_are_jumpers no)
		(fp_line
			(start -0.508 -0.9398)
			(end -0.508 0.9398)
			(stroke
				(width 0.1524)
				(type default)
			)
			(layer "F.SilkS")
		)
		(fp_line
			(start 0.508 -0.9398)
			(end -0.508 -0.9398)
			(stroke
				(width 0.1524)
				(type default)
			)
			(layer "F.SilkS")
		)
		(fp_rect
			(start -0.508 0.9398)
			(end 0.508 -0.9398)
			(stroke
				(width 0)
				(type default)
			)
			(fill no)
			(layer "F.CrtYd")
		)
		(fp_rect
			(start -0.508 0.9398)
			(end 0.508 -0.9398)
			(stroke
				(width 0)
				(type default)
			)
			(fill no)
			(layer "F.Fab")
		)
		(pad "1" smd custom
			(at 0 -0.4445 270)
			(size 0.1397 0.1397)
			(layers "F.Cu" "F.Mask" "F.Paste")
			(net "DUT_TDI_R")
			(options
				(clearance outline)
				(anchor circle)
			)
			(primitives
				(gr_poly
					(pts
						(arc
							(start -0.1778 -0.2794)
							(mid -0.249642 -0.249642)
							(end -0.2794 -0.1778)
						)
						(arc
							(start -0.2794 0.1778)
							(mid -0.249642 0.249642)
							(end -0.1778 0.2794)
						)
						(arc
							(start 0.1778 0.2794)
							(mid 0.249642 0.249642)
							(end 0.2794 0.1778)
						)
						(arc
							(start 0.2794 -0.1778)
							(mid 0.249642 -0.249642)
							(end 0.1778 -0.2794)
						)
					)
					(width 0)
					(fill yes)
				)
			)
		)
		(pad "2" smd custom
			(at 0 0.4445 270)
			(size 0.1397 0.1397)
			(layers "F.Cu" "F.Mask" "F.Paste")
			(net "DUT_TDI")
			(options
				(clearance outline)
				(anchor circle)
			)
			(primitives
				(gr_poly
					(pts
						(arc
							(start -0.1778 -0.2794)
							(mid -0.249642 -0.249642)
							(end -0.2794 -0.1778)
						)
						(arc
							(start -0.2794 0.1778)
							(mid -0.249642 0.249642)
							(end -0.1778 0.2794)
						)
						(arc
							(start 0.1778 0.2794)
							(mid 0.249642 0.249642)
							(end 0.2794 0.1778)
						)
						(arc
							(start 0.2794 -0.1778)
							(mid 0.249642 -0.249642)
							(end 0.1778 -0.2794)
						)
					)
					(width 0)
					(fill yes)
				)
			)
		)
	)
)
